(kicad_pcb
	(version 20260206)
	(generator "pcbnew")
	(generator_version "10.0")
	(general
		(thickness 1.6)
		(legacy_teardrops no)
	)
	(paper "A4")
	(title_block
		(title "01162023_DA0F0TEBIF0_F0T_Expander_BD_F_brd_V02_OCP.brd")
		(comment 1 "Grand Teton / footprints 5370-5375 of 9728")
	)
	(layers
		(0 "F.Cu" signal "TOP")
		(4 "In1.Cu" signal "GND")
		(6 "In2.Cu" signal "VCC")
		(8 "In3.Cu" signal "VCC1")
		(10 "In4.Cu" signal "GND1")
		(12 "In5.Cu" signal "IN1")
		(14 "In6.Cu" signal "GND2")
		(16 "In7.Cu" signal "IN2")
		(18 "In8.Cu" signal "GND3")
		(20 "In9.Cu" signal "IN3")
		(22 "In10.Cu" signal "GND4")
		(24 "In11.Cu" signal "IN4")
		(26 "In12.Cu" signal "GND5")
		(28 "In13.Cu" signal "IN5")
		(30 "In14.Cu" signal "GND6")
		(32 "In15.Cu" signal "IN6")
		(34 "In16.Cu" signal "GND7")
		(2 "B.Cu" signal "BOTTOM")
		(9 "F.Adhes" user "F.Adhesive")
		(11 "B.Adhes" user "B.Adhesive")
		(13 "F.Paste" user "Package Geometry/Pastemask Top")
		(15 "B.Paste" user "Package Geometry/Pastemask Bottom")
		(5 "F.SilkS" user "Ref Des/Silkscreen Top")
		(7 "B.SilkS" user "Ref Des/Silkscreen Bottom")
		(1 "F.Mask" user "Board Geometry/Soldermask Top")
		(3 "B.Mask" user "Board Geometry/Soldermask Bottom")
		(17 "Dwgs.User" user "User.Drawings")
		(19 "Cmts.User" user "User.Comments")
		(21 "Eco1.User" user "User.Eco1")
		(23 "Eco2.User" user "User.Eco2")
		(25 "Edge.Cuts" user "Board Geometry/Outline")
		(27 "Margin" user)
		(31 "F.CrtYd" user "Package Geometry/Place Bound Top")
		(29 "B.CrtYd" user "Package Geometry/Place Bound Bottom")
		(35 "F.Fab" user "Ref Des/Assembly Top")
		(33 "B.Fab" user "Ref Des/Assembly Bottom")
	)
	(footprint ""
		(layer "F.Cu")
		(at 114.132106 -284.8991 180)
		(property "Reference" "PU8"
			(at -23.263606 -1.566672 90)
			(unlocked yes)
			(layer "F.SilkS")
			(effects
				(font
					(size 0.7874 0.5842)
					(thickness 0.1524)
				)
			)
		)
		(property "Value" ""
			(at 0 0 180)
			(layer "F.Fab")
			(effects
				(font
					(size 1.27 1.27)
				)
			)
		)
		(duplicate_pad_numbers_are_jumpers no)
		(fp_line
			(start 2.500122 2.999994)
			(end 2.2987 2.999994)
			(stroke
				(width 0.1524)
				(type default)
			)
			(layer "F.SilkS")
		)
		(fp_line
			(start 2.500122 2.339594)
			(end 2.500122 2.999994)
			(stroke
				(width 0.1524)
				(type default)
			)
			(layer "F.SilkS")
		)
		(fp_line
			(start 2.500122 -2.999994)
			(end 2.500122 -2.44348)
			(stroke
				(width 0.1524)
				(type default)
			)
			(layer "F.SilkS")
		)
		(fp_line
			(start 2.31394 -2.999994)
			(end 2.500122 -2.999994)
			(stroke
				(width 0.1524)
				(type default)
			)
			(layer "F.SilkS")
		)
		(fp_line
			(start -2.2987 2.999994)
			(end -2.500122 2.999994)
			(stroke
				(width 0.1524)
				(type default)
			)
			(layer "F.SilkS")
		)
		(fp_line
			(start -2.500122 2.999994)
			(end -2.500122 2.339594)
			(stroke
				(width 0.1524)
				(type default)
			)
			(layer "F.SilkS")
		)
		(fp_line
			(start -2.500122 0.6604)
			(end -2.500122 0.229108)
			(stroke
				(width 0.1524)
				(type default)
			)
			(layer "F.SilkS")
		)
		(fp_line
			(start -2.500122 -2.529078)
			(end -2.500122 -2.999994)
			(stroke
				(width 0.1524)
				(type default)
			)
			(layer "F.SilkS")
		)
		(fp_line
			(start -2.500122 -2.999994)
			(end -2.24409 -2.999994)
			(stroke
				(width 0.1524)
				(type default)
			)
			(layer "F.SilkS")
		)
		(fp_poly
			(pts
				(xy -2.239518 -3.936238) (xy -3.255518 -3.936238) (xy -2.747518 -2.920238)
			)
			(stroke
				(width 0)
				(type default)
			)
			(fill yes)
			(layer "F.SilkS")
		)
		(fp_line
			(start 2.500122 2.999994)
			(end -2.500122 2.999994)
			(stroke
				(width 0.1)
				(type default)
			)
			(layer "F.Fab")
		)
		(fp_line
			(start 2.500122 -2.999994)
			(end 2.500122 2.999994)
			(stroke
				(width 0.1)
				(type default)
			)
			(layer "F.Fab")
		)
		(fp_line
			(start -2.500122 2.999994)
			(end -2.500122 -2.999994)
			(stroke
				(width 0.1)
				(type default)
			)
			(layer "F.Fab")
		)
		(fp_line
			(start -2.500122 -2.999994)
			(end 2.500122 -2.999994)
			(stroke
				(width 0.1)
				(type default)
			)
			(layer "F.Fab")
		)
		(fp_poly
			(pts
				(xy -4.218432 -2.783078) (xy -4.218432 -1.767078) (xy -3.202432 -2.275078)
			)
			(stroke
				(width 0)
				(type default)
			)
			(fill yes)
			(layer "F.Fab")
		)
		(pad "1" smd rect
			(at -2.400046 -2.275078 270)
			(size 0.2286 0.6096)
			(layers "F.Cu" "F.Mask" "F.Paste")
			(net "SW_P0V8_PEX0_VOS2")
		)
		(pad "2" smd rect
			(at -2.400046 -1.82499 270)
			(size 0.2286 0.6096)
			(layers "F.Cu" "F.Mask" "F.Paste")
			(net "GND")
		)
		(pad "3" smd rect
			(at -2.400046 -1.374902 270)
			(size 0.2286 0.6096)
			(layers "F.Cu" "F.Mask" "F.Paste")
			(net "P0V8_PEX0_VCC2")
		)
		(pad "4" smd rect
			(at -2.400046 -0.925068 270)
			(size 0.2286 0.6096)
			(layers "F.Cu" "F.Mask" "F.Paste")
			(net "P0V8_PEX0_PVCC")
		)
		(pad "5" smd rect
			(at -2.400046 -0.47498 270)
			(size 0.2286 0.6096)
			(layers "F.Cu" "F.Mask" "F.Paste")
			(net "GND")
		)
		(pad "6" smd rect
			(at -2.400046 -0.024892 270)
			(size 0.2286 0.6096)
			(layers "F.Cu" "F.Mask" "F.Paste")
			(net "NC_P0V8_PEX0_PH2_NC1")
		)
		(pad "7_9-20_24" smd circle
			(at 0 1.150112 270)
			(size 0 0)
			(layers "F.Cu" "F.Mask" "F.Paste")
			(net "GND")
		)
		(pad "10_19" smd rect
			(at 0 2.899918 270)
			(size 0.6096 4.318)
			(layers "F.Cu" "F.Mask" "F.Paste")
			(net "SW_P0V8_PEX0_PH2")
		)
		(pad "25_29" smd rect
			(at 1.549908 -1.279906 90)
			(size 2.0574 2.3114)
			(layers "F.Cu" "F.Mask" "F.Paste")
			(net "SW_P12V_P0V8_PEX0_FLT")
		)
		(pad "30" smd rect
			(at 2.05994 -2.899918 180)
			(size 0.2286 0.6096)
			(layers "F.Cu" "F.Mask" "F.Paste")
			(net "SW_P12V_P0V8_PEX0_FLT")
		)
		(pad "31" smd rect
			(at 1.610106 -2.899918 180)
			(size 0.2286 0.6096)
			(layers "F.Cu" "F.Mask" "F.Paste")
			(net "NC_P0V8_PEX0_PH2_NC3")
		)
		(pad "32" smd rect
			(at 1.160018 -2.899918 180)
			(size 0.2286 0.6096)
			(layers "F.Cu" "F.Mask" "F.Paste")
			(net "SW_P0V8_PEX0_PHASE2")
		)
		(pad "33" smd rect
			(at 0.70993 -2.899918 180)
			(size 0.2286 0.6096)
			(layers "F.Cu" "F.Mask" "F.Paste")
			(net "SW_P0V8_PEX0_BOOT2")
		)
		(pad "34" smd rect
			(at 0.260096 -2.899918 180)
			(size 0.2286 0.6096)
			(layers "F.Cu" "F.Mask" "F.Paste")
			(net "P0V8_PEX0_PWM2")
		)
		(pad "35" smd rect
			(at -0.189992 -2.899918 180)
			(size 0.2286 0.6096)
			(layers "F.Cu" "F.Mask" "F.Paste")
			(net "P0V8_PEX0_EN2")
		)
		(pad "36" smd rect
			(at -0.64008 -2.899918 180)
			(size 0.2286 0.6096)
			(layers "F.Cu" "F.Mask" "F.Paste")
			(net "P0V8_PEX0_TSEN")
		)
		(pad "37" smd rect
			(at -1.089914 -2.899918 180)
			(size 0.2286 0.6096)
			(layers "F.Cu" "F.Mask" "F.Paste")
			(net "P0V8_PEX0_LSET2")
		)
		(pad "38" smd rect
			(at -1.540002 -2.899918 180)
			(size 0.2286 0.6096)
			(layers "F.Cu" "F.Mask" "F.Paste")
			(net "P0V8_PEX0_ISEN2")
		)
		(pad "39" smd rect
			(at -1.99009 -2.899918 180)
			(size 0.2286 0.6096)
			(layers "F.Cu" "F.Mask" "F.Paste")
			(net "P0V8_PEX0_VREF")
		)
		(pad "40" smd rect
			(at -0.87503 -1.27508 180)
			(size 1.7526 1.9558)
			(layers "F.Cu" "F.Mask" "F.Paste")
			(net "GND")
		)
		(pad "41" smd rect
			(at -1.525016 0.249936 90)
			(size 0.3048 0.4572)
			(layers "F.Cu" "F.Mask" "F.Paste")
			(net "NC_P0V8_PEX0_PH2_NC2")
		)
		(zone
			(layer "F.Cu")
			(hatch none 0.5)
			(connect_pads
				(clearance 0)
			)
			(min_thickness 0.25)
			(keepout
				(tracks not_allowed)
				(vias allowed)
				(pads allowed)
				(copperpour not_allowed)
				(footprints allowed)
			)
			(placement
				(enabled no)
				(sheetname "")
			)
			(fill
				(thermal_gap 0.5)
				(thermal_bridge_width 0.5)
				(island_removal_mode 0)
			)
			(polygon
				(pts
					(xy 116.632228 -287.899094) (xy 116.632228 -287.149794) (xy 111.631984 -287.149794) (xy 111.631984 -287.899094)
					(xy 111.922306 -287.899094) (xy 111.922306 -287.443418) (xy 116.341906 -287.443418) (xy 116.341906 -287.899094)
				)
			)
		)
	)
	(footprint ""
		(layer "F.Cu")
		(at 26.930096 -297.205908 -90)
		(property "Reference" "C3015"
			(at 0 0 270)
			(layer "F.SilkS")
			(hide yes)
			(effects
				(font
					(size 1.27 1.27)
				)
			)
		)
		(property "Value" ""
			(at 0 0 270)
			(layer "F.Fab")
			(effects
				(font
					(size 1.27 1.27)
				)
			)
		)
		(duplicate_pad_numbers_are_jumpers no)
		(fp_line
			(start -1.2954 0.5842)
			(end -1.2954 -0.5842)
			(stroke
				(width 0.1524)
				(type default)
			)
			(layer "F.SilkS")
		)
		(fp_line
			(start 1.2954 0.5842)
			(end -1.2954 0.5842)
			(stroke
				(width 0.1524)
				(type default)
			)
			(layer "F.SilkS")
		)
		(fp_line
			(start -1.2954 -0.5842)
			(end 1.2954 -0.5842)
			(stroke
				(width 0.1524)
				(type default)
			)
			(layer "F.SilkS")
		)
		(fp_line
			(start 1.2954 -0.5842)
			(end 1.2954 0.5842)
			(stroke
				(width 0.1524)
				(type default)
			)
			(layer "F.SilkS")
		)
		(fp_line
			(start -0.8636 0.4572)
			(end -0.8636 0.4064)
			(stroke
				(width 0.1)
				(type default)
			)
			(layer "F.Fab")
		)
		(fp_line
			(start 0.8636 0.4572)
			(end -0.8636 0.4572)
			(stroke
				(width 0.1)
				(type default)
			)
			(layer "F.Fab")
		)
		(fp_line
			(start -1.1938 0.4064)
			(end -1.1938 -0.4064)
			(stroke
				(width 0.1)
				(type default)
			)
			(layer "F.Fab")
		)
		(fp_line
			(start -0.8636 0.4064)
			(end -1.1938 0.4064)
			(stroke
				(width 0.1)
				(type default)
			)
			(layer "F.Fab")
		)
		(fp_line
			(start 0.8636 0.4064)
			(end 0.8636 0.4572)
			(stroke
				(width 0.1)
				(type default)
			)
			(layer "F.Fab")
		)
		(fp_line
			(start 1.1938 0.4064)
			(end 0.8636 0.4064)
			(stroke
				(width 0.1)
				(type default)
			)
			(layer "F.Fab")
		)
		(fp_line
			(start -1.1938 -0.4064)
			(end -0.8636 -0.4064)
			(stroke
				(width 0.1)
				(type default)
			)
			(layer "F.Fab")
		)
		(fp_line
			(start -0.8636 -0.4064)
			(end -0.8636 -0.4572)
			(stroke
				(width 0.1)
				(type default)
			)
			(layer "F.Fab")
		)
		(fp_line
			(start 0.8636 -0.4064)
			(end 1.1938 -0.4064)
			(stroke
				(width 0.1)
				(type default)
			)
			(layer "F.Fab")
		)
		(fp_line
			(start 1.1938 -0.4064)
			(end 1.1938 0.4064)
			(stroke
				(width 0.1)
				(type default)
			)
			(layer "F.Fab")
		)
		(fp_line
			(start -0.8636 -0.4572)
			(end 0.8636 -0.4572)
			(stroke
				(width 0.1)
				(type default)
			)
			(layer "F.Fab")
		)
		(fp_line
			(start 0.8636 -0.4572)
			(end 0.8636 -0.4064)
			(stroke
				(width 0.1)
				(type default)
			)
			(layer "F.Fab")
		)
		(pad "1" smd rect
			(at -0.7366 0 180)
			(size 0.7112 0.8128)
			(layers "F.Cu" "F.Mask" "F.Paste")
			(net "P1V8_PLL0_PEX0")
		)
		(pad "2" smd rect
			(at 0.7366 0 180)
			(size 0.7112 0.8128)
			(layers "F.Cu" "F.Mask" "F.Paste")
			(net "GND")
		)
	)
	(footprint ""
		(layer "F.Cu")
		(at 134.043166 -114.152426 -90)
		(property "Reference" "PC791"
			(at 0 0 270)
			(layer "F.SilkS")
			(hide yes)
			(effects
				(font
					(size 1.27 1.27)
				)
			)
		)
		(property "Value" ""
			(at 0 0 270)
			(layer "F.Fab")
			(effects
				(font
					(size 1.27 1.27)
				)
			)
		)
		(duplicate_pad_numbers_are_jumpers no)
		(fp_line
			(start -1.524 0.762)
			(end -1.524 -0.762)
			(stroke
				(width 0.1524)
				(type default)
			)
			(layer "F.SilkS")
		)
		(fp_line
			(start 1.524 0.762)
			(end -1.524 0.762)
			(stroke
				(width 0.1524)
				(type default)
			)
			(layer "F.SilkS")
		)
		(fp_line
			(start -1.524 -0.762)
			(end 1.524 -0.762)
			(stroke
				(width 0.1524)
				(type default)
			)
			(layer "F.SilkS")
		)
		(fp_line
			(start 1.524 -0.762)
			(end 1.524 0.762)
			(stroke
				(width 0.1524)
				(type default)
			)
			(layer "F.SilkS")
		)
		(fp_line
			(start -1.1049 0.724916)
			(end 1.1049 0.724916)
			(stroke
				(width 0.1)
				(type default)
			)
			(layer "F.Fab")
		)
		(fp_line
			(start 1.1049 0.724916)
			(end 1.1049 -0.724916)
			(stroke
				(width 0.1)
				(type default)
			)
			(layer "F.Fab")
		)
		(fp_line
			(start -1.1049 -0.724916)
			(end -1.1049 0.724916)
			(stroke
				(width 0.1)
				(type default)
			)
			(layer "F.Fab")
		)
		(fp_line
			(start 1.1049 -0.724916)
			(end -1.1049 -0.724916)
			(stroke
				(width 0.1)
				(type default)
			)
			(layer "F.Fab")
		)
		(pad "1" smd rect
			(at -0.889 0 90)
			(size 1.016 1.27)
			(layers "F.Cu" "F.Mask" "F.Paste")
			(net "P3V3_NIC2")
		)
		(pad "2" smd rect
			(at 0.889 0 90)
			(size 1.016 1.27)
			(layers "F.Cu" "F.Mask" "F.Paste")
			(net "GND")
		)
	)
	(footprint ""
		(layer "F.Cu")
		(at 18.019014 -403.41931 90)
		(property "Reference" "R5587"
			(at 0 0 90)
			(layer "F.SilkS")
			(hide yes)
			(effects
				(font
					(size 1.27 1.27)
				)
			)
		)
		(property "Value" ""
			(at 0 0 90)
			(layer "F.Fab")
			(effects
				(font
					(size 1.27 1.27)
				)
			)
		)
		(duplicate_pad_numbers_are_jumpers no)
		(fp_line
			(start 0.7874 -0.4064)
			(end 0.7874 0.4064)
			(stroke
				(width 0.1524)
				(type default)
			)
			(layer "F.SilkS")
		)
		(fp_line
			(start -0.7874 -0.4064)
			(end 0.7874 -0.4064)
			(stroke
				(width 0.1524)
				(type default)
			)
			(layer "F.SilkS")
		)
		(fp_line
			(start 0.7874 0.4064)
			(end -0.7874 0.4064)
			(stroke
				(width 0.1524)
				(type default)
			)
			(layer "F.SilkS")
		)
		(fp_line
			(start -0.7874 0.4064)
			(end -0.7874 -0.4064)
			(stroke
				(width 0.1524)
				(type default)
			)
			(layer "F.SilkS")
		)
		(fp_line
			(start -0.12065 -0.305054)
			(end -0.12065 -0.2794)
			(stroke
				(width 0.1)
				(type default)
			)
			(layer "F.Fab")
		)
		(fp_line
			(start -0.67945 -0.305054)
			(end -0.12065 -0.305054)
			(stroke
				(width 0.1)
				(type default)
			)
			(layer "F.Fab")
		)
		(fp_line
			(start 0.67945 -0.3048)
			(end 0.67945 0.3048)
			(stroke
				(width 0.1)
				(type default)
			)
			(layer "F.Fab")
		)
		(fp_line
			(start 0.12065 -0.3048)
			(end 0.67945 -0.3048)
			(stroke
				(width 0.1)
				(type default)
			)
			(layer "F.Fab")
		)
		(fp_line
			(start 0.12065 -0.2794)
			(end 0.12065 -0.3048)
			(stroke
				(width 0.1)
				(type default)
			)
			(layer "F.Fab")
		)
		(fp_line
			(start -0.12065 -0.2794)
			(end 0.12065 -0.2794)
			(stroke
				(width 0.1)
				(type default)
			)
			(layer "F.Fab")
		)
		(fp_line
			(start 0.120396 0.2794)
			(end -0.12065 0.2794)
			(stroke
				(width 0.1)
				(type default)
			)
			(layer "F.Fab")
		)
		(fp_line
			(start -0.12065 0.2794)
			(end -0.12065 0.3048)
			(stroke
				(width 0.1)
				(type default)
			)
			(layer "F.Fab")
		)
		(fp_line
			(start 0.67945 0.3048)
			(end 0.120396 0.3048)
			(stroke
				(width 0.1)
				(type default)
			)
			(layer "F.Fab")
		)
		(fp_line
			(start 0.120396 0.3048)
			(end 0.120396 0.2794)
			(stroke
				(width 0.1)
				(type default)
			)
			(layer "F.Fab")
		)
		(fp_line
			(start -0.12065 0.3048)
			(end -0.67945 0.3048)
			(stroke
				(width 0.1)
				(type default)
			)
			(layer "F.Fab")
		)
		(fp_line
			(start -0.67945 0.3048)
			(end -0.67945 -0.305054)
			(stroke
				(width 0.1)
				(type default)
			)
			(layer "F.Fab")
		)
		(pad "1" smd circle
			(at -0.40005 0 90)
			(size 0 0)
			(layers "F.Cu" "F.Mask" "F.Paste")
			(net "SMB_BIC_I2C6_MUX_THERMAL_R_SDA")
		)
		(pad "2" smd circle
			(at 0.40005 0 90)
			(size 0 0)
			(layers "F.Cu" "F.Mask" "F.Paste")
			(net "SMB_LM75_0_SDA")
		)
	)
	(footprint ""
		(layer "F.Cu")
		(at 186.026552 -25.432004 -90)
		(property "Reference" "C971"
			(at 0 0 270)
			(layer "F.SilkS")
			(hide yes)
			(effects
				(font
					(size 1.27 1.27)
				)
			)
		)
		(property "Value" ""
			(at 0 0 270)
			(layer "F.Fab")
			(effects
				(font
					(size 1.27 1.27)
				)
			)
		)
		(duplicate_pad_numbers_are_jumpers no)
		(fp_line
			(start -0.7874 0.4064)
			(end -0.7874 -0.4064)
			(stroke
				(width 0.1524)
				(type default)
			)
			(layer "F.SilkS")
		)
		(fp_line
			(start 0.7874 0.4064)
			(end -0.7874 0.4064)
			(stroke
				(width 0.1524)
				(type default)
			)
			(layer "F.SilkS")
		)
		(fp_line
			(start -0.7874 -0.4064)
			(end 0.7874 -0.4064)
			(stroke
				(width 0.1524)
				(type default)
			)
			(layer "F.SilkS")
		)
		(fp_line
			(start 0.7874 -0.4064)
			(end 0.7874 0.4064)
			(stroke
				(width 0.1524)
				(type default)
			)
			(layer "F.SilkS")
		)
		(fp_line
			(start -0.67945 0.3048)
			(end -0.67945 -0.305054)
			(stroke
				(width 0.1)
				(type default)
			)
			(layer "F.Fab")
		)
		(fp_line
			(start -0.12065 0.3048)
			(end -0.67945 0.3048)
			(stroke
				(width 0.1)
				(type default)
			)
			(layer "F.Fab")
		)
		(fp_line
			(start 0.120396 0.3048)
			(end 0.120396 0.2794)
			(stroke
				(width 0.1)
				(type default)
			)
			(layer "F.Fab")
		)
		(fp_line
			(start 0.67945 0.3048)
			(end 0.120396 0.3048)
			(stroke
				(width 0.1)
				(type default)
			)
			(layer "F.Fab")
		)
		(fp_line
			(start -0.12065 0.2794)
			(end -0.12065 0.3048)
			(stroke
				(width 0.1)
				(type default)
			)
			(layer "F.Fab")
		)
		(fp_line
			(start 0.120396 0.2794)
			(end -0.12065 0.2794)
			(stroke
				(width 0.1)
				(type default)
			)
			(layer "F.Fab")
		)
		(fp_line
			(start -0.12065 -0.2794)
			(end 0.12065 -0.2794)
			(stroke
				(width 0.1)
				(type default)
			)
			(layer "F.Fab")
		)
		(fp_line
			(start 0.12065 -0.2794)
			(end 0.12065 -0.3048)
			(stroke
				(width 0.1)
				(type default)
			)
			(layer "F.Fab")
		)
		(fp_line
			(start 0.12065 -0.3048)
			(end 0.67945 -0.3048)
			(stroke
				(width 0.1)
				(type default)
			)
			(layer "F.Fab")
		)
		(fp_line
			(start 0.67945 -0.3048)
			(end 0.67945 0.3048)
			(stroke
				(width 0.1)
				(type default)
			)
			(layer "F.Fab")
		)
		(fp_line
			(start -0.67945 -0.305054)
			(end -0.12065 -0.305054)
			(stroke
				(width 0.1)
				(type default)
			)
			(layer "F.Fab")
		)
		(fp_line
			(start -0.12065 -0.305054)
			(end -0.12065 -0.2794)
			(stroke
				(width 0.1)
				(type default)
			)
			(layer "F.Fab")
		)
		(pad "1" smd circle
			(at -0.40005 0 270)
			(size 0 0)
			(layers "F.Cu" "F.Mask" "F.Paste")
			(net "GND")
		)
		(pad "2" smd circle
			(at 0.40005 0 270)
			(size 0 0)
			(layers "F.Cu" "F.Mask" "F.Paste")
			(net "P3V3_SSD6")
		)
	)
	(footprint ""
		(layer "F.Cu")
		(at 122.077988 -343.952322 90)
		(property "Reference" "C365"
			(at 0 0 90)
			(layer "F.SilkS")
			(hide yes)
			(effects
				(font
					(size 1.27 1.27)
				)
			)
		)
		(property "Value" ""
			(at 0 0 90)
			(layer "F.Fab")
			(effects
				(font
					(size 1.27 1.27)
				)
			)
		)
		(duplicate_pad_numbers_are_jumpers no)
		(fp_line
			(start 0.299974 -0.150114)
			(end 0.299974 0.150114)
			(stroke
				(width 0.1)
				(type default)
			)
			(layer "F.Fab")
		)
		(fp_line
			(start -0.299974 -0.150114)
			(end 0.299974 -0.150114)
			(stroke
				(width 0.1)
				(type default)
			)
			(layer "F.Fab")
		)
		(fp_line
			(start 0.299974 0.150114)
			(end -0.299974 0.150114)
			(stroke
				(width 0.1)
				(type default)
			)
			(layer "F.Fab")
		)
		(fp_line
			(start -0.299974 0.150114)
			(end -0.299974 -0.150114)
			(stroke
				(width 0.1)
				(type default)
			)
			(layer "F.Fab")
		)
		(pad "1" smd rect
			(at -0.2667 0 90)
			(size 0.3048 0.381)
			(layers "F.Cu" "F.Mask" "F.Paste")
			(net "P5E_PEX1_STN6_TX_DN<99>")
		)
		(pad "2" smd rect
			(at 0.2667 0 90)
			(size 0.3048 0.381)
			(layers "F.Cu" "F.Mask" "F.Paste")
			(net "P5E_PEX1_STN6_TX_C_DN<99>")
		)
	)
)
